# BASEBOARD_FAB2 (Tioga Pass) — schematic netlist excerpt (pin names and nets, part order shuffled) for the footprints in the layout excerpt that follows; sources: Cadence DE-HDL packaged netlist, KiCad conversion of Wiwynn_Tioga_Pass_MB.brd

C5T1  CAP_A  47UF 4V 20% X5R  pkg 0603V  page 217 : A = PVDDQ_ABC ; B = GND
C3P21  CAP  0.22UF 16V 10% X7R  pkg 0402  page 107 : A = P3E_CPU0_PE1_SS_TXN<2> ; B = P3E_CPU0_PE1_SS_C_TXN<2>
R4P3  RES  49.9 1% CHIP  pkg 0402  page 21 : A = A_CPU0_PE012_RBIAS ; B = GND

(kicad_pcb
	(version 20260206)
	(generator "pcbnew")
	(generator_version "10.0")
	(general
		(thickness 1.6)
		(legacy_teardrops no)
	)
	(paper "A4")
	(title_block
		(title "Wiwynn_Tioga_Pass_MB.brd")
		(comment 1 "Tioga Pass / footprints 2417-2419 of 4770")
	)
	(layers
		(0 "F.Cu" signal "TOP")
		(4 "In1.Cu" signal "L2GND")
		(6 "In2.Cu" signal "L3")
		(8 "In3.Cu" signal "L4GND")
		(10 "In4.Cu" signal "L5")
		(12 "In5.Cu" signal "L6GND")
		(14 "In6.Cu" signal "L7VCC")
		(16 "In7.Cu" signal "L8VCC")
		(18 "In8.Cu" signal "L9GND")
		(20 "In9.Cu" signal "L10")
		(22 "In10.Cu" signal "L11GND")
		(24 "In11.Cu" signal "L12")
		(26 "In12.Cu" signal "L13GND")
		(2 "B.Cu" signal "BOTTOM")
		(9 "F.Adhes" user "F.Adhesive")
		(11 "B.Adhes" user "B.Adhesive")
		(13 "F.Paste" user "Package Geometry/Pastemask Top")
		(15 "B.Paste" user "Package Geometry/Pastemask Bottom")
		(5 "F.SilkS" user "Ref Des/Silkscreen Top")
		(7 "B.SilkS" user "Ref Des/Silkscreen Bottom")
		(1 "F.Mask" user "Board Geometry/Soldermask Top")
		(3 "B.Mask" user "Board Geometry/Soldermask Bottom")
		(17 "Dwgs.User" user "User.Drawings")
		(19 "Cmts.User" user "User.Comments")
		(21 "Eco1.User" user "User.Eco1")
		(23 "Eco2.User" user "User.Eco2")
		(25 "Edge.Cuts" user "Board Geometry/Outline")
		(27 "Margin" user)
		(31 "F.CrtYd" user "Package Geometry/Place Bound Top")
		(29 "B.CrtYd" user "Package Geometry/Place Bound Bottom")
		(35 "F.Fab" user "Ref Des/Assembly Top")
		(33 "B.Fab" user "Ref Des/Assembly Bottom")
	)
	(footprint ""
		(layer "B.Cu")
		(at 282.259024 -78.039214 -90)
		(property "Reference" "R4P3"
			(at 0 0 90)
			(layer "B.SilkS")
			(hide yes)
			(effects
				(font
					(size 1.27 1.27)
				)
				(justify mirror)
			)
		)
		(property "Value" ""
			(at 0 0 90)
			(layer "B.Fab")
			(effects
				(font
					(size 1.27 1.27)
				)
				(justify mirror)
			)
		)
		(duplicate_pad_numbers_are_jumpers no)
		(fp_rect
			(start 0.2794 0.9906)
			(end -0.2794 -0.1016)
			(stroke
				(width 0)
				(type default)
			)
			(fill no)
			(layer "B.CrtYd")
		)
		(fp_line
			(start -0.2794 0.9906)
			(end -0.2794 -0.1016)
			(stroke
				(width 0.1)
				(type default)
			)
			(layer "B.Fab")
		)
		(fp_line
			(start 0.2794 0.9906)
			(end -0.2794 0.9906)
			(stroke
				(width 0.1)
				(type default)
			)
			(layer "B.Fab")
		)
		(fp_line
			(start -0.2794 -0.1016)
			(end 0.2794 -0.1016)
			(stroke
				(width 0.1)
				(type default)
			)
			(layer "B.Fab")
		)
		(fp_line
			(start 0.2794 -0.1016)
			(end 0.2794 0.9906)
			(stroke
				(width 0.1)
				(type default)
			)
			(layer "B.Fab")
		)
		(pad "1" smd rect
			(at 0 0 90)
			(size 0.508 0.508)
			(layers "B.Cu" "B.Mask" "B.Paste")
			(net "A_CPU0_PE012_RBIAS")
		)
		(pad "2" smd rect
			(at 0 0.889 90)
			(size 0.508 0.508)
			(layers "B.Cu" "B.Mask" "B.Paste")
			(net "GND")
		)
		(zone
			(layer "B.Cu")
			(hatch none 0.5)
			(connect_pads
				(clearance 0)
			)
			(min_thickness 0.25)
			(keepout
				(tracks allowed)
				(vias not_allowed)
				(pads allowed)
				(copperpour not_allowed)
				(footprints allowed)
			)
			(placement
				(enabled no)
				(sheetname "")
			)
			(fill
				(thermal_gap 0.5)
				(thermal_bridge_width 0.5)
				(island_removal_mode 0)
			)
			(polygon
				(pts
					(xy 281.624024 -77.785214) (xy 282.005024 -77.785214) (xy 282.005024 -78.293214) (xy 281.624024 -78.293214)
				)
			)
		)
		(zone
			(layer "B.Cu")
			(hatch none 0.5)
			(connect_pads
				(clearance 0)
			)
			(min_thickness 0.25)
			(keepout
				(tracks not_allowed)
				(vias allowed)
				(pads allowed)
				(copperpour not_allowed)
				(footprints allowed)
			)
			(placement
				(enabled no)
				(sheetname "")
			)
			(fill
				(thermal_gap 0.5)
				(thermal_bridge_width 0.5)
				(island_removal_mode 0)
			)
			(polygon
				(pts
					(xy 281.624024 -77.785214) (xy 282.005024 -77.785214) (xy 282.005024 -78.293214) (xy 281.624024 -78.293214)
				)
			)
		)
	)
	(footprint ""
		(layer "B.Cu")
		(at 345.832176 -77.694536)
		(property "Reference" "C3P21"
			(at 0 0 0)
			(layer "B.SilkS")
			(hide yes)
			(effects
				(font
					(size 1.27 1.27)
				)
				(justify mirror)
			)
		)
		(property "Value" ""
			(at 0 0 0)
			(layer "B.Fab")
			(effects
				(font
					(size 1.27 1.27)
				)
				(justify mirror)
			)
		)
		(duplicate_pad_numbers_are_jumpers no)
		(fp_poly
			(pts
				(xy -0.3048 -0.1016) (xy -0.3048 0.9906) (xy 0.3048 0.9906) (xy 0.3048 -0.1016)
			)
			(stroke
				(width 0)
				(type default)
			)
			(fill no)
			(layer "B.CrtYd")
		)
		(fp_line
			(start -0.3048 -0.1016)
			(end 0.3048 -0.1016)
			(stroke
				(width 0.1)
				(type default)
			)
			(layer "B.Fab")
		)
		(fp_line
			(start -0.3048 0.9906)
			(end -0.3048 -0.1016)
			(stroke
				(width 0.1)
				(type default)
			)
			(layer "B.Fab")
		)
		(fp_line
			(start 0.3048 -0.1016)
			(end 0.3048 0.9906)
			(stroke
				(width 0.1)
				(type default)
			)
			(layer "B.Fab")
		)
		(fp_line
			(start 0.3048 0.9906)
			(end -0.3048 0.9906)
			(stroke
				(width 0.1)
				(type default)
			)
			(layer "B.Fab")
		)
		(pad "1" smd rect
			(at 0 0 180)
			(size 0.508 0.508)
			(layers "B.Cu" "B.Mask" "B.Paste")
			(net "P3E_CPU0_PE1_SS_TXN<2>")
		)
		(pad "2" smd rect
			(at 0 0.889 180)
			(size 0.508 0.508)
			(layers "B.Cu" "B.Mask" "B.Paste")
			(net "P3E_CPU0_PE1_SS_C_TXN<2>")
		)
		(zone
			(layer "B.Cu")
			(hatch none 0.5)
			(connect_pads
				(clearance 0)
			)
			(min_thickness 0.25)
			(keepout
				(tracks allowed)
				(vias not_allowed)
				(pads allowed)
				(copperpour not_allowed)
				(footprints allowed)
			)
			(placement
				(enabled no)
				(sheetname "")
			)
			(fill
				(thermal_gap 0.5)
				(thermal_bridge_width 0.5)
				(island_removal_mode 0)
			)
			(polygon
				(pts
					(xy 346.086176 -77.440536) (xy 345.578176 -77.440536) (xy 345.578176 -77.059536) (xy 346.086176 -77.059536)
				)
			)
		)
	)
	(footprint ""
		(layer "B.Cu")
		(at 244.5004 -27.813 -90)
		(property "Reference" "C5T1"
			(at 0 0 90)
			(layer "B.SilkS")
			(hide yes)
			(effects
				(font
					(size 1.27 1.27)
				)
				(justify mirror)
			)
		)
		(property "Value" ""
			(at 0 0 90)
			(layer "B.Fab")
			(effects
				(font
					(size 1.27 1.27)
				)
				(justify mirror)
			)
		)
		(duplicate_pad_numbers_are_jumpers no)
		(fp_rect
			(start 0.500126 1.598422)
			(end -0.500126 -0.201422)
			(stroke
				(width 0)
				(type default)
			)
			(fill no)
			(layer "B.CrtYd")
		)
		(fp_line
			(start -0.500126 1.598422)
			(end 0.500126 1.598422)
			(stroke
				(width 0.1)
				(type default)
			)
			(layer "B.Fab")
		)
		(fp_line
			(start 0.500126 1.598422)
			(end 0.500126 -0.201422)
			(stroke
				(width 0.1)
				(type default)
			)
			(layer "B.Fab")
		)
		(fp_line
			(start -0.500126 -0.201422)
			(end -0.500126 1.598422)
			(stroke
				(width 0.1)
				(type default)
			)
			(layer "B.Fab")
		)
		(fp_line
			(start 0.500126 -0.201422)
			(end -0.500126 -0.201422)
			(stroke
				(width 0.1)
				(type default)
			)
			(layer "B.Fab")
		)
		(pad "1" smd rect
			(at 0 0 180)
			(size 0.889 0.9906)
			(layers "B.Cu" "B.Mask" "B.Paste")
			(net "PVDDQ_ABC")
		)
		(pad "2" smd rect
			(at 0 1.397 180)
			(size 0.889 0.9906)
			(layers "B.Cu" "B.Mask" "B.Paste")
			(net "GND")
		)
		(zone
			(layer "B.Cu")
			(hatch none 0.5)
			(connect_pads
				(clearance 0)
			)
			(min_thickness 0.25)
			(keepout
				(tracks not_allowed)
				(vias allowed)
				(pads allowed)
				(copperpour not_allowed)
				(footprints allowed)
			)
			(placement
				(enabled no)
				(sheetname "")
			)
			(fill
				(thermal_gap 0.5)
				(thermal_bridge_width 0.5)
				(island_removal_mode 0)
			)
			(polygon
				(pts
					(xy 243.5479 -27.3177) (xy 244.0559 -27.3177) (xy 244.0559 -28.3083) (xy 243.5479 -28.3083)
				)
			)
		)
		(zone
			(layer "B.Cu")
			(hatch none 0.5)
			(connect_pads
				(clearance 0)
			)
			(min_thickness 0.25)
			(keepout
				(tracks allowed)
				(vias not_allowed)
				(pads allowed)
				(copperpour not_allowed)
				(footprints allowed)
			)
			(placement
				(enabled no)
				(sheetname "")
			)
			(fill
				(thermal_gap 0.5)
				(thermal_bridge_width 0.5)
				(island_removal_mode 0)
			)
			(polygon
				(pts
					(xy 243.5479 -27.3177) (xy 244.0559 -27.3177) (xy 244.0559 -28.3083) (xy 243.5479 -28.3083)
				)
			)
		)
	)
)
